FILE_TYPE = CONNECTIVITY;
{Allegro Design Entry HDL 16.6-p007 (v16-6-112F) 10/10/2012}
"PAGE_NUMBER" = 218;
0"NC";
1"GND\g";
2"PVCCIO_CPU0\g";
3"GND\g";
4"GND\g";
5"GND\g";
6"GND\g";
7"GND\g";
8"GND\g";
9"P3V3_STBY\g";
10"GND\g";
11"GND\g";
12"GND\g";
13"P3V3_STBY\g";
14"PVCCIO_CPU0\g";
15"PWRGD_PVDDQ_DEF_R";
16"VR_PVDDQ_DEF_VD12";
17"SVID_ALERT1_CPU0_R_N";
18"SMB_VR_STBY_LVC3_SCL";
19"SVID_DIO1_CPU0_R";
20"VR_PVDDQ_DEF_PWM1";
21"SVID_VDIO_PVDDQ_DEF";
22"VR_PVDDQ_DEF_VD12";
23"TP_PVDDQ_DEF_MP1";
24"PU_VR_PVDDQ_DEF_FAULT1";
25"SMB_VR_STBY_LVC3_SDA";
26"TP_PVDDQ_DEF_MP2";
27"PWRGD_PVDDQ_DEF";
28"SVID_ALERT_PVDDQ_DEF";
29"IRQ_PVDDQ_DEF_VRHOT_LVT3_R_N";
30"VR_PVDDQ_DEF_AIREF2";
31"VR_PVDDQ_DEF_VREN";
32"ISENSE_PVDDQ_DEF_PH2_IMON";
33"SVID_CLK_PVDDQ_DEF";
34"SVID_CLK1_CPU0_R";
35"ISENSE_PVDDQ_DEF_PH1_IMON";
36"VR_PVDDQ_DEF_AIREF1";
37"VSENSE_PVDDQ_DEF_N";
38"VR_PVDDQ_DEF_AVSP";
39"A_TSENSE_PVDDQ_DEF";
40"VR_PVDDQ_DEF_AIINSEN";
41"VR_PVDDQ_DEF_VDD";
42"VR_PVDDQ_DEF_XADDR1";
43"VR_PVDDQ_DEF_XADDR2";
44"VR_PVDDQ_DEF_VINSEN";
45"VSENSE_PVDDQ_DEF_P";
46"FM_PVDDQ_DEF_EN";
47"VR_PVDDQ_DEF_PWM2";
48"IRQ_PVDDQ_DEF_VRHOT_LVT3_N";
%"GND"
"1","(-1250,-250)","0","mstr_symbols","I1";
;
ROOM"VDDQ_DEF_PWR_VR"
BODY_TYPE"PLUMBING"
CDS_LIB"mstr_symbols"
VOLTAGE"0"
HDL_POWER"GND"
SIZE"1B";
"A\NAC"1;
%"RES"
"1","(-2925,875)","0","mstr_discrete","I13";
;
PART_NUMBER"G21796-066"
VALUE"10.0"
WATTAGE"1/16W"
MATERIAL"CHIP"
PACK_TYPE"0402"
TOLERANCE"1%"
LOCATION"R7A7"
CDS_SEC"1"
CDS_LIB"mstr_discrete"
CDS_LOCATION"R7A7"
SEC_TYPE"0402"
SEC"1"
ROOM"VDDQ_DEF_PWR_VR";
"B"
$PN"2"38;
"A"
$PN"1"45;
%"CAP"
"1","(-2650,725)","0","mstr_discrete","I14";
;
PACK_TYPE"0402LF"
PART_NUMBER"A36096-050"
VOLTAGE"50V"
MATERIAL"X7R"
VALUE"220PF"
LOCATION"C7A28"
TOLERANCE"10%"
CDS_SEC"1"
CDS_LIB"mstr_discrete"
CDS_LOCATION"C7A28"
ROOM"VDDQ_DEF_PWR_VR"
SEC"1"
SEC_TYPE"0402LF";
"A"
$PN"1"38;
"B"
$PN"2"37;
%"RES"
"1","(-2900,1200)","0","mstr_discrete","I15";
;
PACK_TYPE"0402"
TOLERANCE"5%"
WATTAGE"1/16W"
VALUE"0.0"
PART_NUMBER"G21497-005"
LOCATION"R3M6"
MATERIAL"CHIP"
CDS_SEC"1"
ROOM"VDDQ_DEF_PWR_VR"
CDS_LOCATION"R3M6"
CDS_LIB"mstr_discrete"
SEC"1"
SEC_TYPE"0402";
"B"
$PN"2"31;
"A"
$PN"1"46;
%"CAP"
"1","(-1250,450)","2","mstr_discrete","I16";
;
LOCATION"C7A29"
PART_NUMBER"A36096-050"
MATERIAL"X7R"
PACK_TYPE"0402LF"
VOLTAGE"50V"
TOLERANCE"10%"
VALUE"220PF"
CDS_SEC"1"
SEC_TYPE"0402LF"
CDS_LIB"mstr_discrete"
ROOM"VDDQ_DEF_PWR_VR"
CDS_LOCATION"C7A29"
SEC"1";
"A"
$PN"1"39;
"B"
$PN"2"1;
%"SC22P50V2JN-4GP"
"1","(-2200,2250)","1","w_hdl","I17";
;
GROUP"POWER_FAIR"
VALUE"SC22P50V2JN-4GP"
PACK_SIZE"0402"
RATED"50V"
TYPE"NPO"
ATTRIBUTE"22PF"
TOLERANCE"5%"
LOCATION"CF17"
CDS_LMAN_SYM_OUTLINE"-50,25,50,-25"
CDS_LIB"w_hdl"
PART_NUMBER"78.22034.1FL"
PACK_TYPE"SMD-BCG"
CDS_LOCATION"CF17"
$SEC"1"
CDS_SEC"1";
"2"
$PN"2"35;
"1"
$PN"1"36;
%"RES"
"1","(-2200,2400)","0","mstr_discrete","I18";
;
CDS_SEC"1"
GROUP"POWER_FAIR"
FAIR_SS"064.9530D.M001"
PACK_TYPE"0402"
PART_NUMBER"G85996-004"
LOCATION"RF17"
VALUE"1.0K"
TOLERANCE"0.1%"
MATERIAL"CHIP"
WATTAGE"1/16W"
CDS_LOCATION"RF17"
CDS_LIB"mstr_discrete"
ROOM"SB"
SEC_TYPE"0402"
SEC"1";
"B"
$PN"2"35;
"A"
$PN"1"36;
%"RES"
"1","(-1550,2400)","0","mstr_discrete","I19";
;
CDS_SEC"1"
VALUE"1.0K"
LOCATION"RF18"
TOLERANCE"0.1%"
PART_NUMBER"G85996-004"
MATERIAL"CHIP"
WATTAGE"1/16W"
PACK_TYPE"0402"
BOM_SS"NOPOP"
GROUP"POWER_FAIR"
CDS_LIB"mstr_discrete"
ROOM"SB"
CDS_LOCATION"RF18"
SEC_TYPE"0402"
SEC"1";
"B"
$PN"2"32;
"A"
$PN"1"30;
%"SC22P50V2JN-4GP"
"1","(-1550,2250)","1","w_hdl","I20";
;
BOM_SS"NOPOP"
LOCATION"CF18"
ATTRIBUTE"22PF"
TOLERANCE"5%"
RATED"50V"
TYPE"NPO"
PACK_SIZE"0402"
VALUE"SC22P50V2JN-4GP"
GROUP"POWER_FAIR"
PART_NUMBER"78.22034.1FL"
PACK_TYPE"SMD-BCG"
CDS_LMAN_SYM_OUTLINE"-50,25,50,-25"
CDS_LIB"w_hdl"
CDS_LOCATION"CF18"
$SEC"1"
CDS_SEC"1";
"2"
$PN"2"32;
"1"
$PN"1"30;
%"RES"
"1","(-1475,2725)","0","mstr_discrete","I21";
;
TOLERANCE"1%"
WATTAGE"1/16W"
PACK_TYPE"0402"
MATERIAL"CHIP"
PART_NUMBER"G21796-009"
VALUE"150.0"
LOCATION"R7A17"
CDS_SEC"1"
CDS_LIB"mstr_discrete"
CDS_LOCATION"R7A17"
ROOM"VDDQ_DEF_PWR_VR"
SEC"1"
SEC_TYPE"0402";
"B"
$PN"2"33;
"A"
$PN"1"34;
%"PVCCIO_CPU0"
"1","(-1900,3675)","0","mstr_symbols","I23";
;
HDL_POWER"PVCCIO_CPU0"
BODY_TYPE"PLUMBING"
CDS_LIB"mstr_symbols"
VOLTAGE"1.1V";
"G\NAC"2;
%"GND"
"1","(-1175,550)","0","mstr_symbols","I24";
;
ROOM"VDDQ_DEF_PWR_VR"
BODY_TYPE"PLUMBING"
HDL_POWER"GND"
CDS_LIB"mstr_symbols"
VOLTAGE"0"
SIZE"1B";
"A\NAC"3;
%"GND"
"1","(-1075,-400)","0","mstr_symbols","I25";
;
HDL_POWER"GND"
VOLTAGE"0"
CDS_LIB"mstr_symbols"
SIZE"1B"
BODY_TYPE"PLUMBING"
ROOM"VDDQ_DEF_PWR_VR";
"A\NAC"4;
%"GND"
"1","(-775,-400)","0","mstr_symbols","I26";
;
HDL_POWER"GND"
VOLTAGE"0"
BODY_TYPE"PLUMBING"
SIZE"1B"
CDS_LIB"mstr_symbols"
ROOM"VDDQ_DEF_PWR_VR";
"A\NAC"5;
%"GND"
"1","(1950,-300)","0","mstr_symbols","I27";
;
ROOM"VDDQ_DEF_PWR_VR"
VOLTAGE"0"
CDS_LIB"mstr_symbols"
BODY_TYPE"PLUMBING"
HDL_POWER"GND"
SIZE"1B";
"A\NAC"6;
%"CAP_A"
"1","(1950,-100)","0","dev_discrete","I28";
;
PACK_TYPE"0402V"
PART_NUMBER"A36096-030"
MATERIAL"X7R"
TOLERANCE"10%"
VOLTAGE"16V"
VALUE"0.1UF"
LOCATION"C7B2"
CDS_LIB"dev_discrete"
SEC"1"
CDS_SEC"1"
CDS_LOCATION"C7B2"
ROOM"VDDQ_DEF_PWR_VR"
SEC_TYPE"0402V";
"B"
$PN"2"6;
"A"
$PN"1"16;
%"GND"
"1","(2350,-375)","0","mstr_symbols","I29";
;
ROOM"VDDQ_DEF_PWR_VR"
BODY_TYPE"PLUMBING"
VOLTAGE"0"
CDS_LIB"mstr_symbols"
HDL_POWER"GND"
SIZE"1B";
"A\NAC"7;
%"CAP_A"
"1","(2350,-100)","0","dev_discrete","I30";
;
PACK_TYPE"0402V"
PART_NUMBER"D97712-004"
MATERIAL"X6S"
TOLERANCE"10%"
VOLTAGE"6.3V"
VALUE"1.0UF"
LOCATION"C7B1"
CDS_LIB"dev_discrete"
CDS_LOCATION"C7B1"
CDS_SEC"1"
SEC_TYPE"0402V"
SEC"1"
ROOM"VDDQ_DEF_PWR_VR";
"B"
$PN"2"7;
"A"
$PN"1"16;
%"GND"
"1","(725,525)","0","mstr_symbols","I33";
;
ROOM"VDDQ_DEF_PWR_VR"
VOLTAGE"0"
CDS_LIB"mstr_symbols"
SIZE"1B"
BODY_TYPE"PLUMBING"
HDL_POWER"GND";
"A\NAC"8;
%"RES"
"2","(-1150,3225)","0","mstr_discrete","I34";
;
PACK_TYPE"0402"
PART_NUMBER"G21796-010"
MATERIAL"EMPTY"
WATTAGE"1/16W"
TOLERANCE"1%"
VALUE"100.0K"
LOCATION"R3M5"
CDS_SEC"1"
CDS_LIB"mstr_discrete"
CDS_LOCATION"R3M5"
ROOM"VDDQ_DEF_PWR_VR"
BOM_COST"SM_CONTROLLER"
SEC"1"
SEC_TYPE"0402";
"A"
$PN"1"9;
"B"
$PN"2"31;
%"RES"
"2","(-450,3150)","0","mstr_discrete","I35";
;
PACK_TYPE"0402"
PART_NUMBER"G21497-005"
MATERIAL"CHIP"
WATTAGE"1/16W"
TOLERANCE"5%"
VALUE"0.0"
LOCATION"R3M1"
CDS_SEC"1"
CDS_LIB"mstr_discrete"
SEC_TYPE"0402"
SEC"1"
CDS_LOCATION"R3M1"
ROOM"VDDQ_DEF_PWR_VR";
"A"
$PN"1"9;
"B"
$PN"2"41;
%"P3V3_STBY"
"1","(-450,3650)","0","mstr_symbols","I36";
;
HDL_POWER"P3V3_STBY"
BODY_TYPE"PLUMBING"
VOLTAGE"3.3V"
CDS_LIB"mstr_symbols"
SIZE"1B";
"G\NAC"9;
%"GND"
"1","(-150,2600)","0","mstr_symbols","I37";
;
ROOM"VDDQ_DEF_PWR_VR"
BODY_TYPE"PLUMBING"
VOLTAGE"0"
SIZE"1B"
CDS_LIB"mstr_symbols"
HDL_POWER"GND";
"A\NAC"10;
%"CAP_A"
"1","(-150,2800)","0","dev_discrete","I38";
;
MATERIAL"X7R"
PACK_TYPE"0402V"
PART_NUMBER"A36096-030"
TOLERANCE"10%"
VOLTAGE"16V"
VALUE"0.1UF"
LOCATION"C7A38"
CDS_LOCATION"C7A38"
CDS_LIB"dev_discrete"
CDS_SEC"1"
ROOM"VDDQ_DEF_PWR_VR"
SEC_TYPE"0402V"
SEC"1";
"B"
$PN"2"10;
"A"
$PN"1"41;
%"GND"
"1","(250,2600)","0","mstr_symbols","I39";
;
ROOM"VDDQ_DEF_PWR_VR"
BODY_TYPE"PLUMBING"
VOLTAGE"0"
CDS_LIB"mstr_symbols"
SIZE"1B"
HDL_POWER"GND";
"A\NAC"11;
%"CAP_A"
"1","(250,2800)","0","dev_discrete","I40";
;
PART_NUMBER"D97712-004"
PACK_TYPE"0402V"
MATERIAL"X6S"
TOLERANCE"10%"
VOLTAGE"6.3V"
VALUE"1.0UF"
LOCATION"C7A37"
CDS_LIB"dev_discrete"
CDS_LOCATION"C7A37"
ROOM"VDDQ_DEF_PWR_VR"
CDS_SEC"1"
SEC_TYPE"0402V"
SEC"1";
"B"
$PN"2"11;
"A"
$PN"1"41;
%"CAP"
"1","(1625,925)","0","mstr_discrete","I41";
;
PACK_TYPE"0402LF"
MATERIAL"X7R"
PART_NUMBER"A36096-046"
LOCATION"C7B3"
TOLERANCE"10%"
VOLTAGE"50V"
VALUE"1000PF"
CDS_SEC"1"
CDS_LIB"mstr_discrete"
ROOM"VDDQ_DEF_PWR_VR"
CDS_LOCATION"C7B3"
SEC"1"
SEC_TYPE"0402LF";
"A"
$PN"1"15;
"B"
$PN"2"12;
%"GND"
"1","(1625,700)","0","mstr_symbols","I42";
;
ROOM"VDDQ_DEF_PWR_VR"
HDL_POWER"GND"
VOLTAGE"0"
CDS_LIB"mstr_symbols"
BODY_TYPE"PLUMBING"
SIZE"1B";
"A\NAC"12;
%"RES"
"1","(1500,1400)","0","mstr_discrete","I45";
;
MATERIAL"CHIP"
LOCATION"R7A12"
PART_NUMBER"G21497-005"
WATTAGE"1/16W"
VALUE"0.0"
TOLERANCE"5%"
PACK_TYPE"0402"
CDS_SEC"1"
CDS_LIB"mstr_discrete"
SEC_TYPE"0402"
SEC"1"
CDS_LOCATION"R7A12"
ROOM"VDDQ_DEF_PWR_VR";
"B"
$PN"2"19;
"A"
$PN"1"21;
%"RES"
"1","(1825,1550)","0","mstr_discrete","I46";
;
WATTAGE"1/16W"
PART_NUMBER"G21497-005"
VALUE"0.0"
LOCATION"R12W29"
TOLERANCE"5%"
MATERIAL"EMPTY"
PACK_TYPE"0402"
CDS_SEC"1"
CDS_LOCATION"R12W29"
BOM_COST"MEM_NV"
SEC_TYPE"0402"
ROOM"NV_DIMM"
SEC"1"
CDS_LIB"mstr_discrete";
"B"
$PN"2"27;
"A"
$PN"1"23;
%"RES"
"1","(1825,1950)","0","mstr_discrete","I55";
;
MATERIAL"EMPTY"
VALUE"0.0"
LOCATION"R12W30"
TOLERANCE"5%"
WATTAGE"1/16W"
PACK_TYPE"0402"
PART_NUMBER"G21497-005"
CDS_SEC"1"
CDS_LOCATION"R12W30"
CDS_LIB"mstr_discrete"
SEC"1"
ROOM"NV_DIMM"
SEC_TYPE"0402"
BOM_COST"MEM_NV";
"B"
$PN"2"27;
"A"
$PN"1"26;
%"RES"
"1","(1350,2100)","0","mstr_discrete","I56";
;
VALUE"0.0"
PART_NUMBER"G21497-005"
TOLERANCE"5%"
LOCATION"R7A11"
WATTAGE"1/16W"
MATERIAL"CHIP"
PACK_TYPE"0402"
CDS_SEC"1"
CDS_LIB"mstr_discrete"
CDS_LOCATION"R7A11"
ROOM"VDDQ_DEF_PWR_VR"
SEC_TYPE"0402"
SEC"1";
"B"
$PN"2"17;
"A"
$PN"1"28;
%"RES"
"2","(975,2800)","0","mstr_discrete","I57";
;
MATERIAL"CHIP"
PACK_TYPE"0402"
PART_NUMBER"G21796-026"
WATTAGE"1/16W"
TOLERANCE"1%"
VALUE"1.00K"
LOCATION"R7B4"
CDS_SEC"1"
CDS_LIB"mstr_discrete"
CDS_LOCATION"R7B4"
SEC_TYPE"0402"
SEC"1"
ROOM"VDDQ_DEF_PWR_VR";
"A"
$PN"1"13;
"B"
$PN"2"29;
%"RES"
"2","(1175,2800)","0","mstr_discrete","I58";
;
MATERIAL"CHIP"
LOCATION"R7B5"
VALUE"1.00K"
TOLERANCE"1%"
WATTAGE"1/16W"
PACK_TYPE"0402"
PART_NUMBER"G21796-026"
CDS_SEC"1"
CDS_LOCATION"R7B5"
CDS_LIB"mstr_discrete"
ROOM"VDDQ_DEF_PWR_VR"
SEC"1"
SEC_TYPE"0402";
"A"
$PN"1"13;
"B"
$PN"2"15;
%"RES"
"1","(1825,2150)","0","mstr_discrete","I59";
;
MATERIAL"CHIP"
TOLERANCE"1%"
VALUE"33.2"
PACK_TYPE"0402"
WATTAGE"1/16W"
LOCATION"R7B1"
PART_NUMBER"G21796-074"
CDS_SEC"1"
SEC_TYPE"0402"
SEC"1"
CDS_LOCATION"R7B1"
CDS_LIB"mstr_discrete";
"B"
$PN"2"48;
"A"
$PN"1"29;
%"RES"
"1","(1925,2250)","0","mstr_discrete","I60";
;
PART_NUMBER"G21796-250"
LOCATION"R3M3"
POP"NOPOP"
TOLERANCE"1.0%"
VALUE"22.1"
WATTAGE"1/16W"
MATERIAL"CHIP"
PACK_TYPE"0402"
CDS_SEC"1"
ROOM"VDDQ_DEF_PWR_VR"
CDS_LOCATION"R3M3"
CDS_LIB"mstr_discrete"
SEC"1"
SEC_TYPE"0402";
"B"
$PN"2"27;
"A"
$PN"1"15;
%"P3V3_STBY"
"1","(1375,3475)","0","mstr_symbols","I62";
;
HDL_POWER"P3V3_STBY"
BODY_TYPE"PLUMBING"
VOLTAGE"3.3V"
CDS_LIB"mstr_symbols"
SIZE"1B";
"G\NAC"13;
%"RES"
"2","(2700,2625)","0","mstr_discrete","I67";
;
PART_NUMBER"G21796-017"
LOCATION"R3L11"
MATERIAL"EMPTY"
WATTAGE"1/16W"
PACK_TYPE"0402"
VALUE"100.0"
TOLERANCE"1%"
SEC_TYPE"0402"
SEC"1"
CDS_LOCATION"R3L11"
ROOM"VDDQ_DEF_PWR_VR"
CDS_LIB"mstr_discrete"
CDS_SEC"1";
"A"
$PN"1"14;
"B"
$PN"2"19;
%"PVCCIO_CPU0"
"1","(2700,2850)","0","mstr_symbols","I68";
;
VOLTAGE"1.1V"
CDS_LIB"mstr_symbols"
BODY_TYPE"PLUMBING"
HDL_POWER"PVCCIO_CPU0";
"G\NAC"14;
%"PXM1310B"
"2","(150,1500)","0","mstr_controller","I69";
;
PART_NUMBER"H89186-001"
LOCATION"EU7A5"
MATERIAL"IC"
CDS_SEC"1"
CDS_LIB"mstr_controller"
CDS_LMAN_SYM_OUTLINE"-400,900,400,-900"
CDS_LOCATION"EU7A5"
PACK_TYPE"QFN"
SEC_TYPE"QFN"
SEC"1";
"MP2"
$PN"18"26;
"THPAD"
$PN"41"8;
"BPWM1"
$PN"1"0;
"APWM1"
$PN"5"20;
"APWM2"
$PN"4"47;
"APWM3"
$PN"3"0;
"SDA"
$PN"6"25;
"SCL"
$PN"7"18;
"VCLK"
$PN"15"33;
"VDIO"
$PN"16"21;
"RESET_N \B"
$PN"8"0;
"XADDR1"
$PN"36"42;
"AISEN3"
$PN"26"0;
"AIREF3"
$PN"25"0;
"XADDR2"
$PN"33"43;
"AISEN2"
$PN"24"32;
"AIREF2"
$PN"23"30;
"ATSEN"
$PN"35"39;
"AISEN1"
$PN"22"35;
"AIREF1"
$PN"21"36;
"VDD"
$PN"39"41;
"BTSEN"
$PN"34"0;
"BISEN1"
$PN"32"3;
"BIREF1"
$PN"31"0;
"DNC<0>"
$PN"2"0;
"DNC<1>"
$PN"28"0;
"VRHOT_N \B"
$PN"11"29;
"PINALRT_N \B"
$PN"12"0;
"VALRT_N \B"
$PN"17"28;
"AVSEN"
$PN"19"38;
"AVREF"
$PN"20"37;
"BVSEN"
$PN"29"0;
"BVREF"
$PN"30"0;
"VINSEN"
$PN"37"44;
"VD12"
$PN"40"22;
"GND"
$PN"27"8;
"IINSEN"
$PN"38"40;
"AVRRDY"
$PN"9"15;
"AVREN"
$PN"10"31;
"MP0"
$PN"13"24;
"MP1"
$PN"14"23;
%"RES"
"2","(-1900,3250)","0","mstr_discrete","I70";
;
LOCATION"R3L13"
VALUE"49.9"
WATTAGE"1/16W"
PART_NUMBER"G21796-047"
TOLERANCE"1%"
MATERIAL"EMPTY"
PACK_TYPE"0402"
CDS_LOCATION"R3L13"
CDS_SEC"1"
CDS_LIB"mstr_discrete"
ROOM"VDDQ_ABC_PWR_VR"
SEC"1"
SEC_TYPE"0402";
"A"
$PN"1"2;
"B"
$PN"2"34;
%"RES"
"2","(-1075,-150)","0","mstr_discrete","I73";
;
PACK_TYPE"0402"
WATTAGE"1/16W"
LOCATION"R7A10"
TOLERANCE"1.0%"
PART_NUMBER"G21796-317"
VALUE"16K"
MATERIAL"CHIP"
CDS_LOCATION"R7A10"
CDS_SEC"1"
SEC_TYPE"0402"
CDS_LIB"mstr_discrete"
SEC"1"
ROOM"VDDQ_ABC_PWR_VR";
"A"
$PN"1"42;
"B"
$PN"2"4;
%"RES"
"2","(-775,-150)","0","mstr_discrete","I74";
;
PART_NUMBER"G21796-311"
PACK_TYPE"0402"
WATTAGE"1/16W"
LOCATION"R7A8"
VALUE"2.26K"
TOLERANCE"1.0%"
MATERIAL"CHIP"
CDS_LOCATION"R7A8"
CDS_SEC"1"
SEC_TYPE"0402"
SEC"1"
BOM_COST"SM_CONTROLLER"
ROOM"SMBUS"
SKU"B"
CDS_LIB"mstr_discrete";
"A"
$PN"1"43;
"B"
$PN"2"5;
%"RES"
"1","(1825,1600)","0","mstr_discrete","I75";
;
LOCATION"R12W28"
TOLERANCE"5%"
PART_NUMBER"G21497-005"
VALUE"0.0"
WATTAGE"1/16W"
PACK_TYPE"0402"
CDS_LOCATION"R12W28"
CDS_SEC"1"
CDS_LIB"mstr_discrete"
BOM_COST"PROC_SIDEBAND"
MATERIAL"CHIP"
ROOM"CPU0"
SEC_TYPE"0402"
SEC"1";
"B"
$PN"2"27;
"A"
$PN"1"24;
%"RES"
"2","(2150,2800)","0","mstr_discrete","I76";
;
CDS_SEC"1"
WATTAGE"1/16W"
PART_NUMBER"G21796-311"
MATERIAL"CHIP"
PACK_TYPE"0402"
TOLERANCE"1.0%"
VALUE"2.26K"
LOCATION"R7A9"
CDS_LOCATION"R7A9"
CDS_LIB"mstr_discrete"
SKU"B"
ROOM"SMBUS"
BOM_COST"SM_CONTROLLER"
SEC"1"
SEC_TYPE"0402";
"A"
$PN"1"13;
"B"
$PN"2"27;
END.
